# T6G (Grand Teton) — schematic netlist excerpt (pin names and nets, part order shuffled) for the footprints in the layout excerpt that follows; sources: Cadence DE-HDL packaged netlist, KiCad conversion of 04192023_DAF0TMB3IC0_F0TG_MB_C_brd_V02_OCP.brd

PR3839  Q_RES  10K 1% CHIP  pkg 0402LF  page 135 : A = P12V_OCP_FLTB_1 ; B = P3V3_AUX
C6693  Q_CAP_DIFFBUS  DIFF BUS_0.22UF 6.3V 20% X6S  pkg C0201  page 341 : \1\ = P5E_CPU1_P2_TX_BUF_C_DP<0> ; \2\ = P5E_CPU1_P2_TX_BUF_DP<0>
PC117  Q_CAP  0.22UF 16V 10% X7R  pkg 0402  page 203 : A = SW_PVDDCR_CPU1_P0_BOOT6_R ; B = SW_PVDDCR_CPU1_P0_BOOTR6

(kicad_pcb
	(version 20260206)
	(generator "pcbnew")
	(generator_version "10.0")
	(general
		(thickness 1.6)
		(legacy_teardrops no)
	)
	(paper "A4")
	(title_block
		(title "04192023_DAF0TMB3IC0_F0TG_MB_C_brd_V02_OCP.brd")
		(comment 1 "Grand Teton / footprints 4297-4299 of 8354")
	)
	(layers
		(0 "F.Cu" signal "TOP")
		(4 "In1.Cu" signal "GND")
		(6 "In2.Cu" signal "IN1")
		(8 "In3.Cu" signal "GND1")
		(10 "In4.Cu" signal "IN2")
		(12 "In5.Cu" signal "GND2")
		(14 "In6.Cu" signal "IN3")
		(16 "In7.Cu" signal "GND3")
		(18 "In8.Cu" signal "VCC")
		(20 "In9.Cu" signal "VCC1")
		(22 "In10.Cu" signal "GND4")
		(24 "In11.Cu" signal "IN4")
		(26 "In12.Cu" signal "GND5")
		(28 "In13.Cu" signal "IN5")
		(30 "In14.Cu" signal "GND6")
		(32 "In15.Cu" signal "IN6")
		(34 "In16.Cu" signal "GND7")
		(2 "B.Cu" signal "BOTTOM")
		(9 "F.Adhes" user "F.Adhesive")
		(11 "B.Adhes" user "B.Adhesive")
		(13 "F.Paste" user "Package Geometry/Pastemask Top")
		(15 "B.Paste" user "Package Geometry/Pastemask Bottom")
		(5 "F.SilkS" user "Ref Des/Silkscreen Top")
		(7 "B.SilkS" user "Ref Des/Silkscreen Bottom")
		(1 "F.Mask" user "Board Geometry/Soldermask Top")
		(3 "B.Mask" user "Board Geometry/Soldermask Bottom")
		(17 "Dwgs.User" user "User.Drawings")
		(19 "Cmts.User" user "User.Comments")
		(21 "Eco1.User" user "User.Eco1")
		(23 "Eco2.User" user "User.Eco2")
		(25 "Edge.Cuts" user "Board Geometry/Outline")
		(27 "Margin" user)
		(31 "F.CrtYd" user "Package Geometry/Place Bound Top")
		(29 "B.CrtYd" user "Package Geometry/Place Bound Bottom")
		(35 "F.Fab" user "Ref Des/Assembly Top")
		(33 "B.Fab" user "Ref Des/Assembly Bottom")
	)
	(footprint ""
		(layer "F.Cu")
		(at 353.451922 -344.586306 -90)
		(property "Reference" "PC117"
			(at 0 0 270)
			(layer "F.SilkS")
			(hide yes)
			(effects
				(font
					(size 1.27 1.27)
				)
			)
		)
		(property "Value" ""
			(at 0 0 270)
			(layer "F.Fab")
			(effects
				(font
					(size 1.27 1.27)
				)
			)
		)
		(duplicate_pad_numbers_are_jumpers no)
		(fp_line
			(start -0.7874 0.4064)
			(end -0.7874 -0.4064)
			(stroke
				(width 0.1524)
				(type default)
			)
			(layer "F.SilkS")
		)
		(fp_line
			(start 0.7874 0.4064)
			(end -0.7874 0.4064)
			(stroke
				(width 0.1524)
				(type default)
			)
			(layer "F.SilkS")
		)
		(fp_line
			(start -0.7874 -0.4064)
			(end 0.7874 -0.4064)
			(stroke
				(width 0.1524)
				(type default)
			)
			(layer "F.SilkS")
		)
		(fp_line
			(start 0.7874 -0.4064)
			(end 0.7874 0.4064)
			(stroke
				(width 0.1524)
				(type default)
			)
			(layer "F.SilkS")
		)
		(fp_line
			(start -0.67945 0.3048)
			(end -0.67945 -0.305054)
			(stroke
				(width 0.1)
				(type default)
			)
			(layer "F.Fab")
		)
		(fp_line
			(start -0.12065 0.3048)
			(end -0.67945 0.3048)
			(stroke
				(width 0.1)
				(type default)
			)
			(layer "F.Fab")
		)
		(fp_line
			(start 0.120396 0.3048)
			(end 0.120396 0.2794)
			(stroke
				(width 0.1)
				(type default)
			)
			(layer "F.Fab")
		)
		(fp_line
			(start 0.67945 0.3048)
			(end 0.120396 0.3048)
			(stroke
				(width 0.1)
				(type default)
			)
			(layer "F.Fab")
		)
		(fp_line
			(start -0.12065 0.2794)
			(end -0.12065 0.3048)
			(stroke
				(width 0.1)
				(type default)
			)
			(layer "F.Fab")
		)
		(fp_line
			(start 0.120396 0.2794)
			(end -0.12065 0.2794)
			(stroke
				(width 0.1)
				(type default)
			)
			(layer "F.Fab")
		)
		(fp_line
			(start -0.12065 -0.2794)
			(end 0.12065 -0.2794)
			(stroke
				(width 0.1)
				(type default)
			)
			(layer "F.Fab")
		)
		(fp_line
			(start 0.12065 -0.2794)
			(end 0.12065 -0.3048)
			(stroke
				(width 0.1)
				(type default)
			)
			(layer "F.Fab")
		)
		(fp_line
			(start 0.12065 -0.3048)
			(end 0.67945 -0.3048)
			(stroke
				(width 0.1)
				(type default)
			)
			(layer "F.Fab")
		)
		(fp_line
			(start 0.67945 -0.3048)
			(end 0.67945 0.3048)
			(stroke
				(width 0.1)
				(type default)
			)
			(layer "F.Fab")
		)
		(fp_line
			(start -0.67945 -0.305054)
			(end -0.12065 -0.305054)
			(stroke
				(width 0.1)
				(type default)
			)
			(layer "F.Fab")
		)
		(fp_line
			(start -0.12065 -0.305054)
			(end -0.12065 -0.2794)
			(stroke
				(width 0.1)
				(type default)
			)
			(layer "F.Fab")
		)
		(pad "1" smd circle
			(at -0.40005 0 270)
			(size 0 0)
			(layers "F.Cu" "F.Mask" "F.Paste")
			(net "SW_PVDDCR_CPU1_P0_BOOT6_R")
		)
		(pad "2" smd circle
			(at 0.40005 0 270)
			(size 0 0)
			(layers "F.Cu" "F.Mask" "F.Paste")
			(net "SW_PVDDCR_CPU1_P0_BOOTR6")
		)
	)
	(footprint ""
		(layer "F.Cu")
		(at 115.783106 -408.517344 -90)
		(property "Reference" "C6693"
			(at 0 0 270)
			(layer "F.SilkS")
			(hide yes)
			(effects
				(font
					(size 1.27 1.27)
				)
			)
		)
		(property "Value" ""
			(at 0 0 270)
			(layer "F.Fab")
			(effects
				(font
					(size 1.27 1.27)
				)
			)
		)
		(duplicate_pad_numbers_are_jumpers no)
		(fp_line
			(start -0.299974 0.150114)
			(end -0.299974 -0.150114)
			(stroke
				(width 0.1)
				(type default)
			)
			(layer "F.Fab")
		)
		(fp_line
			(start 0.299974 0.150114)
			(end -0.299974 0.150114)
			(stroke
				(width 0.1)
				(type default)
			)
			(layer "F.Fab")
		)
		(fp_line
			(start -0.299974 -0.150114)
			(end 0.299974 -0.150114)
			(stroke
				(width 0.1)
				(type default)
			)
			(layer "F.Fab")
		)
		(fp_line
			(start 0.299974 -0.150114)
			(end 0.299974 0.150114)
			(stroke
				(width 0.1)
				(type default)
			)
			(layer "F.Fab")
		)
		(pad "1" smd rect
			(at -0.2667 0 270)
			(size 0.3048 0.381)
			(layers "F.Cu" "F.Mask" "F.Paste")
			(net "P5E_CPU1_P2_TX_BUF_C_DP<0>")
		)
		(pad "2" smd rect
			(at 0.2667 0 270)
			(size 0.3048 0.381)
			(layers "F.Cu" "F.Mask" "F.Paste")
			(net "P5E_CPU1_P2_TX_BUF_DP<0>")
		)
	)
	(footprint ""
		(layer "F.Cu")
		(at 437.875172 -29.684218 180)
		(property "Reference" "PR3839"
			(at 0 0 180)
			(layer "F.SilkS")
			(hide yes)
			(effects
				(font
					(size 1.27 1.27)
				)
			)
		)
		(property "Value" ""
			(at 0 0 180)
			(layer "F.Fab")
			(effects
				(font
					(size 1.27 1.27)
				)
			)
		)
		(duplicate_pad_numbers_are_jumpers no)
		(fp_line
			(start 0.7874 0.4064)
			(end -0.7874 0.4064)
			(stroke
				(width 0.1524)
				(type default)
			)
			(layer "F.SilkS")
		)
		(fp_line
			(start 0.7874 -0.4064)
			(end 0.7874 0.4064)
			(stroke
				(width 0.1524)
				(type default)
			)
			(layer "F.SilkS")
		)
		(fp_line
			(start -0.7874 0.4064)
			(end -0.7874 -0.4064)
			(stroke
				(width 0.1524)
				(type default)
			)
			(layer "F.SilkS")
		)
		(fp_line
			(start -0.7874 -0.4064)
			(end 0.7874 -0.4064)
			(stroke
				(width 0.1524)
				(type default)
			)
			(layer "F.SilkS")
		)
		(fp_line
			(start 0.67945 0.3048)
			(end 0.120396 0.3048)
			(stroke
				(width 0.1)
				(type default)
			)
			(layer "F.Fab")
		)
		(fp_line
			(start 0.67945 -0.3048)
			(end 0.67945 0.3048)
			(stroke
				(width 0.1)
				(type default)
			)
			(layer "F.Fab")
		)
		(fp_line
			(start 0.12065 -0.2794)
			(end 0.12065 -0.3048)
			(stroke
				(width 0.1)
				(type default)
			)
			(layer "F.Fab")
		)
		(fp_line
			(start 0.12065 -0.3048)
			(end 0.67945 -0.3048)
			(stroke
				(width 0.1)
				(type default)
			)
			(layer "F.Fab")
		)
		(fp_line
			(start 0.120396 0.3048)
			(end 0.120396 0.2794)
			(stroke
				(width 0.1)
				(type default)
			)
			(layer "F.Fab")
		)
		(fp_line
			(start 0.120396 0.2794)
			(end -0.12065 0.2794)
			(stroke
				(width 0.1)
				(type default)
			)
			(layer "F.Fab")
		)
		(fp_line
			(start -0.12065 0.3048)
			(end -0.67945 0.3048)
			(stroke
				(width 0.1)
				(type default)
			)
			(layer "F.Fab")
		)
		(fp_line
			(start -0.12065 0.2794)
			(end -0.12065 0.3048)
			(stroke
				(width 0.1)
				(type default)
			)
			(layer "F.Fab")
		)
		(fp_line
			(start -0.12065 -0.2794)
			(end 0.12065 -0.2794)
			(stroke
				(width 0.1)
				(type default)
			)
			(layer "F.Fab")
		)
		(fp_line
			(start -0.12065 -0.305054)
			(end -0.12065 -0.2794)
			(stroke
				(width 0.1)
				(type default)
			)
			(layer "F.Fab")
		)
		(fp_line
			(start -0.67945 0.3048)
			(end -0.67945 -0.305054)
			(stroke
				(width 0.1)
				(type default)
			)
			(layer "F.Fab")
		)
		(fp_line
			(start -0.67945 -0.305054)
			(end -0.12065 -0.305054)
			(stroke
				(width 0.1)
				(type default)
			)
			(layer "F.Fab")
		)
		(pad "1" smd circle
			(at -0.40005 0 180)
			(size 0 0)
			(layers "F.Cu" "F.Mask" "F.Paste")
			(net "P12V_OCP_FLTB_1")
		)
		(pad "2" smd circle
			(at 0.40005 0 180)
			(size 0 0)
			(layers "F.Cu" "F.Mask" "F.Paste")
			(net "P3V3_AUX")
		)
	)
)
